(kicad_pcb
	(version 20260206)
	(generator "pcbnew")
	(generator_version "10.0")
	(general
		(thickness 1.6)
		(legacy_teardrops no)
	)
	(paper "A4")
	(title_block
		(title "peb — Lightning_PEB_BRD.brd")
		(comment 1 "Lightning (Wiwynn / Facebook NVMe JBOF) / footprints 1503-1509 of 2563")
	)
	(layers
		(0 "F.Cu" signal "TOP")
		(4 "In1.Cu" signal "L2GND")
		(6 "In2.Cu" signal "L3")
		(8 "In3.Cu" signal "L4VCC")
		(10 "In4.Cu" signal "L5VCC")
		(12 "In5.Cu" signal "L6")
		(14 "In6.Cu" signal "L7GND")
		(2 "B.Cu" signal "BOTTOM")
		(9 "F.Adhes" user "F.Adhesive")
		(11 "B.Adhes" user "B.Adhesive")
		(13 "F.Paste" user "Package Geometry/Pastemask Top")
		(15 "B.Paste" user "Package Geometry/Pastemask Bottom")
		(5 "F.SilkS" user "Ref Des/Silkscreen Top")
		(7 "B.SilkS" user "Ref Des/Silkscreen Bottom")
		(1 "F.Mask" user "Board Geometry/Soldermask Top")
		(3 "B.Mask" user "Board Geometry/Soldermask Bottom")
		(17 "Dwgs.User" user "User.Drawings")
		(19 "Cmts.User" user "User.Comments")
		(21 "Eco1.User" user "User.Eco1")
		(23 "Eco2.User" user "User.Eco2")
		(25 "Edge.Cuts" user "Board Geometry/Outline")
		(27 "Margin" user)
		(31 "F.CrtYd" user "Package Geometry/Place Bound Top")
		(29 "B.CrtYd" user "Package Geometry/Place Bound Bottom")
		(35 "F.Fab" user "Ref Des/Assembly Top")
		(33 "B.Fab" user "Ref Des/Assembly Bottom")
	)
	(footprint ""
		(layer "F.Cu")
		(at 20.955 -141.859 -90)
		(property "Reference" "R324"
			(at 0 0 270)
			(layer "F.SilkS")
			(hide yes)
			(effects
				(font
					(size 1.27 1.27)
				)
			)
		)
		(property "Value" "10KR2F-2-GP"
			(at 0.064008 -3.993896 270)
			(unlocked yes)
			(layer "F.Fab")
			(hide yes)
			(effects
				(font
					(size 1.016 1.016)
					(thickness 0.1524)
				)
			)
		)
		(property "Device Type" "R402H16"
			(at 0.064008 -5.517896 270)
			(unlocked yes)
			(layer "F.Fab")
			(hide yes)
			(effects
				(font
					(size 1.016 1.016)
					(thickness 0.1524)
				)
			)
		)
		(duplicate_pad_numbers_are_jumpers no)
		(fp_line
			(start -0.508 -0.9398)
			(end -0.508 0.9398)
			(stroke
				(width 0.1524)
				(type default)
			)
			(layer "F.SilkS")
		)
		(fp_line
			(start 0.508 -0.9398)
			(end -0.508 -0.9398)
			(stroke
				(width 0.1524)
				(type default)
			)
			(layer "F.SilkS")
		)
		(fp_rect
			(start -0.508 0.9398)
			(end 0.508 -0.9398)
			(stroke
				(width 0)
				(type default)
			)
			(fill no)
			(layer "F.CrtYd")
		)
		(fp_rect
			(start -0.508 0.9398)
			(end 0.508 -0.9398)
			(stroke
				(width 0)
				(type default)
			)
			(fill no)
			(layer "F.Fab")
		)
		(pad "1" smd custom
			(at 0 -0.4445 270)
			(size 0.1397 0.1397)
			(layers "F.Cu" "F.Mask" "F.Paste")
			(net "PECI0_R")
			(options
				(clearance outline)
				(anchor circle)
			)
			(primitives
				(gr_poly
					(pts
						(arc
							(start -0.1778 -0.2794)
							(mid -0.249642 -0.249642)
							(end -0.2794 -0.1778)
						)
						(arc
							(start -0.2794 0.1778)
							(mid -0.249642 0.249642)
							(end -0.1778 0.2794)
						)
						(arc
							(start 0.1778 0.2794)
							(mid 0.249642 0.249642)
							(end 0.2794 0.1778)
						)
						(arc
							(start 0.2794 -0.1778)
							(mid 0.249642 -0.249642)
							(end 0.1778 -0.2794)
						)
					)
					(width 0)
					(fill yes)
				)
			)
		)
		(pad "2" smd custom
			(at 0 0.4445 270)
			(size 0.1397 0.1397)
			(layers "F.Cu" "F.Mask" "F.Paste")
			(net "GND")
			(options
				(clearance outline)
				(anchor circle)
			)
			(primitives
				(gr_poly
					(pts
						(arc
							(start -0.1778 -0.2794)
							(mid -0.249642 -0.249642)
							(end -0.2794 -0.1778)
						)
						(arc
							(start -0.2794 0.1778)
							(mid -0.249642 0.249642)
							(end -0.1778 0.2794)
						)
						(arc
							(start 0.1778 0.2794)
							(mid 0.249642 0.249642)
							(end 0.2794 0.1778)
						)
						(arc
							(start 0.2794 -0.1778)
							(mid 0.249642 -0.249642)
							(end 0.1778 -0.2794)
						)
					)
					(width 0)
					(fill yes)
				)
			)
		)
	)
	(footprint ""
		(layer "F.Cu")
		(at 28.1178 -198.7042)
		(property "Reference" "Q23"
			(at 0 0 0)
			(layer "F.SilkS")
			(hide yes)
			(effects
				(font
					(size 1.27 1.27)
				)
			)
		)
		(property "Value" "PSMN0R9-25YLC-GP"
			(at -4.2799 -0.4572 0)
			(unlocked yes)
			(layer "F.Fab")
			(hide yes)
			(effects
				(font
					(size 1.016 1.016)
					(thickness 0.1524)
				)
			)
		)
		(property "Device Type" "LFPAK-5PH48-U"
			(at -4.2799 -1.9812 0)
			(unlocked yes)
			(layer "F.Fab")
			(hide yes)
			(effects
				(font
					(size 1.016 1.016)
					(thickness 0.1524)
				)
			)
		)
		(duplicate_pad_numbers_are_jumpers no)
		(fp_line
			(start -2.7559 -6.5532)
			(end -2.7559 1.0668)
			(stroke
				(width 0.1524)
				(type default)
			)
			(layer "F.SilkS")
		)
		(fp_line
			(start -2.7559 1.0668)
			(end 2.7559 1.0668)
			(stroke
				(width 0.1524)
				(type default)
			)
			(layer "F.SilkS")
		)
		(fp_line
			(start -1.7272 1.1684)
			(end -2.1082 1.1684)
			(stroke
				(width 0.3302)
				(type default)
			)
			(layer "F.SilkS")
		)
		(fp_line
			(start 2.7559 -6.5532)
			(end -2.7559 -6.5532)
			(stroke
				(width 0.1524)
				(type default)
			)
			(layer "F.SilkS")
		)
		(fp_line
			(start 2.7559 1.0668)
			(end 2.7559 -6.5532)
			(stroke
				(width 0.1524)
				(type default)
			)
			(layer "F.SilkS")
		)
		(fp_poly
			(pts
				(xy -2.3368 1.5748) (xy -1.905 1.143) (xy -1.4732 1.5748)
			)
			(stroke
				(width 0)
				(type default)
			)
			(fill yes)
			(layer "F.SilkS")
		)
		(fp_poly
			(pts
				(xy -2.5019 -4.02971) (xy -0.3302 -4.02971) (xy -0.3302 -6.30301) (xy -2.5019 -6.30301)
			)
			(stroke
				(width 0)
				(type default)
			)
			(fill yes)
			(layer "F.Paste")
		)
		(fp_poly
			(pts
				(xy -2.5019 -1.09601) (xy -0.3302 -1.09601) (xy -0.3302 -3.36931) (xy -2.5019 -3.36931)
			)
			(stroke
				(width 0)
				(type default)
			)
			(fill yes)
			(layer "F.Paste")
		)
		(fp_poly
			(pts
				(xy 0.3302 -4.02971) (xy 2.5019 -4.02971) (xy 2.5019 -6.30301) (xy 0.3302 -6.30301)
			)
			(stroke
				(width 0)
				(type default)
			)
			(fill yes)
			(layer "F.Paste")
		)
		(fp_poly
			(pts
				(xy 0.3302 -1.09601) (xy 2.5019 -1.09601) (xy 2.5019 -3.36931) (xy 0.3302 -3.36931)
			)
			(stroke
				(width 0)
				(type default)
			)
			(fill yes)
			(layer "F.Paste")
		)
		(fp_rect
			(start -2.4511 0.3048)
			(end 2.4511 -5.6896)
			(stroke
				(width 0)
				(type default)
			)
			(fill no)
			(layer "F.CrtYd")
		)
		(fp_poly
			(pts
				(xy -3.0099 1.3208) (xy -3.0099 -6.8072) (xy 3.0099 -6.8072) (xy 3.0099 -1.016) (xy 2.4511 -1.016)
				(xy 2.4511 -5.6896) (xy -2.4511 -5.6896) (xy -2.4511 0.3048) (xy 2.4511 0.3048) (xy 2.4511 -1.0033)
				(xy 3.0099 -1.0033) (xy 3.0099 1.3208)
			)
			(stroke
				(width 0)
				(type default)
			)
			(fill no)
			(layer "F.CrtYd")
		)
		(fp_rect
			(start -3.0099 1.3208)
			(end 3.0099 -6.8072)
			(stroke
				(width 0)
				(type default)
			)
			(fill no)
			(layer "F.Fab")
		)
		(pad "1" smd rect
			(at -1.905 0)
			(size 0.762 1.6256)
			(layers "F.Cu" "F.Mask" "F.Paste")
			(net "P12V")
		)
		(pad "2" smd rect
			(at -0.635 0)
			(size 0.762 1.6256)
			(layers "F.Cu" "F.Mask" "F.Paste")
			(net "P12V")
		)
		(pad "3" smd rect
			(at 0.635 0)
			(size 0.762 1.6256)
			(layers "F.Cu" "F.Mask" "F.Paste")
			(net "P12V")
		)
		(pad "4" smd rect
			(at 1.905 0)
			(size 0.762 1.6256)
			(layers "F.Cu" "F.Mask" "F.Paste")
			(net "MB0_12V_CTRL_GATE1")
		)
		(pad "5" smd rect
			(at 0 -3.69951)
			(size 5.0038 5.207)
			(layers "F.Cu" "F.Mask" "F.Paste")
			(net "MB0_P12V_MAIN_R")
		)
	)
	(footprint ""
		(layer "F.Cu")
		(at 26.4668 -173.2026 -90)
		(property "Reference" "PR34"
			(at 0 0 270)
			(layer "F.SilkS")
			(hide yes)
			(effects
				(font
					(size 1.27 1.27)
				)
			)
		)
		(property "Value" "10KR2F-2-GP"
			(at 0.064008 -3.993896 270)
			(unlocked yes)
			(layer "F.Fab")
			(hide yes)
			(effects
				(font
					(size 1.016 1.016)
					(thickness 0.1524)
				)
			)
		)
		(property "Device Type" "R402H16"
			(at 0.064008 -5.517896 270)
			(unlocked yes)
			(layer "F.Fab")
			(hide yes)
			(effects
				(font
					(size 1.016 1.016)
					(thickness 0.1524)
				)
			)
		)
		(duplicate_pad_numbers_are_jumpers no)
		(fp_line
			(start -0.508 -0.9398)
			(end -0.508 0.9398)
			(stroke
				(width 0.1524)
				(type default)
			)
			(layer "F.SilkS")
		)
		(fp_line
			(start 0.508 -0.9398)
			(end -0.508 -0.9398)
			(stroke
				(width 0.1524)
				(type default)
			)
			(layer "F.SilkS")
		)
		(fp_rect
			(start -0.508 0.9398)
			(end 0.508 -0.9398)
			(stroke
				(width 0)
				(type default)
			)
			(fill no)
			(layer "F.CrtYd")
		)
		(fp_rect
			(start -0.508 0.9398)
			(end 0.508 -0.9398)
			(stroke
				(width 0)
				(type default)
			)
			(fill no)
			(layer "F.Fab")
		)
		(pad "1" smd custom
			(at 0 -0.4445 270)
			(size 0.1397 0.1397)
			(layers "F.Cu" "F.Mask" "F.Paste")
			(net "GND")
			(options
				(clearance outline)
				(anchor circle)
			)
			(primitives
				(gr_poly
					(pts
						(arc
							(start -0.1778 -0.2794)
							(mid -0.249642 -0.249642)
							(end -0.2794 -0.1778)
						)
						(arc
							(start -0.2794 0.1778)
							(mid -0.249642 0.249642)
							(end -0.1778 0.2794)
						)
						(arc
							(start 0.1778 0.2794)
							(mid 0.249642 0.249642)
							(end 0.2794 0.1778)
						)
						(arc
							(start 0.2794 -0.1778)
							(mid 0.249642 -0.249642)
							(end 0.1778 -0.2794)
						)
					)
					(width 0)
					(fill yes)
				)
			)
		)
		(pad "2" smd custom
			(at 0 0.4445 270)
			(size 0.1397 0.1397)
			(layers "F.Cu" "F.Mask" "F.Paste")
			(net "PCIE_MATED#_A")
			(options
				(clearance outline)
				(anchor circle)
			)
			(primitives
				(gr_poly
					(pts
						(arc
							(start -0.1778 -0.2794)
							(mid -0.249642 -0.249642)
							(end -0.2794 -0.1778)
						)
						(arc
							(start -0.2794 0.1778)
							(mid -0.249642 0.249642)
							(end -0.1778 0.2794)
						)
						(arc
							(start 0.1778 0.2794)
							(mid 0.249642 0.249642)
							(end 0.2794 0.1778)
						)
						(arc
							(start 0.2794 -0.1778)
							(mid 0.249642 -0.249642)
							(end 0.1778 -0.2794)
						)
					)
					(width 0)
					(fill yes)
				)
			)
		)
	)
	(footprint ""
		(layer "F.Cu")
		(at 259.08 -26.289 180)
		(property "Reference" "R742"
			(at 0 0 180)
			(layer "F.SilkS")
			(hide yes)
			(effects
				(font
					(size 1.27 1.27)
				)
			)
		)
		(property "Value" "4K7R2F-GP"
			(at 0.064008 -3.993896 180)
			(unlocked yes)
			(layer "F.Fab")
			(hide yes)
			(effects
				(font
					(size 1.016 1.016)
					(thickness 0.1524)
				)
			)
		)
		(property "Device Type" "R402H16"
			(at 0.064008 -5.517896 180)
			(unlocked yes)
			(layer "F.Fab")
			(hide yes)
			(effects
				(font
					(size 1.016 1.016)
					(thickness 0.1524)
				)
			)
		)
		(duplicate_pad_numbers_are_jumpers no)
		(fp_line
			(start 0.508 -0.9398)
			(end -0.508 -0.9398)
			(stroke
				(width 0.1524)
				(type default)
			)
			(layer "F.SilkS")
		)
		(fp_line
			(start -0.508 -0.9398)
			(end -0.508 0.9398)
			(stroke
				(width 0.1524)
				(type default)
			)
			(layer "F.SilkS")
		)
		(fp_rect
			(start -0.508 0.9398)
			(end 0.508 -0.9398)
			(stroke
				(width 0)
				(type default)
			)
			(fill no)
			(layer "F.CrtYd")
		)
		(fp_rect
			(start -0.508 0.9398)
			(end 0.508 -0.9398)
			(stroke
				(width 0)
				(type default)
			)
			(fill no)
			(layer "F.Fab")
		)
		(pad "1" smd custom
			(at 0 -0.4445 180)
			(size 0.1397 0.1397)
			(layers "F.Cu" "F.Mask" "F.Paste")
			(net "P3V3_GPIO")
			(options
				(clearance outline)
				(anchor circle)
			)
			(primitives
				(gr_poly
					(pts
						(arc
							(start -0.1778 -0.2794)
							(mid -0.249642 -0.249642)
							(end -0.2794 -0.1778)
						)
						(arc
							(start -0.2794 0.1778)
							(mid -0.249642 0.249642)
							(end -0.1778 0.2794)
						)
						(arc
							(start 0.1778 0.2794)
							(mid 0.249642 0.249642)
							(end 0.2794 0.1778)
						)
						(arc
							(start 0.2794 -0.1778)
							(mid 0.249642 -0.249642)
							(end 0.1778 -0.2794)
						)
					)
					(width 0)
					(fill yes)
				)
			)
		)
		(pad "2" smd custom
			(at 0 0.4445 180)
			(size 0.1397 0.1397)
			(layers "F.Cu" "F.Mask" "F.Paste")
			(net "IOEXP_INT#_1")
			(options
				(clearance outline)
				(anchor circle)
			)
			(primitives
				(gr_poly
					(pts
						(arc
							(start -0.1778 -0.2794)
							(mid -0.249642 -0.249642)
							(end -0.2794 -0.1778)
						)
						(arc
							(start -0.2794 0.1778)
							(mid -0.249642 0.249642)
							(end -0.1778 0.2794)
						)
						(arc
							(start 0.1778 0.2794)
							(mid 0.249642 0.249642)
							(end 0.2794 0.1778)
						)
						(arc
							(start 0.2794 -0.1778)
							(mid 0.249642 -0.249642)
							(end 0.1778 -0.2794)
						)
					)
					(width 0)
					(fill yes)
				)
			)
		)
	)
	(footprint ""
		(layer "F.Cu")
		(at 243.098574 -16.414496 -90)
		(property "Reference" "R494"
			(at 0 0 270)
			(layer "F.SilkS")
			(hide yes)
			(effects
				(font
					(size 1.27 1.27)
				)
			)
		)
		(property "Value" "0R2J-2-GP"
			(at 0.064008 -3.993896 270)
			(unlocked yes)
			(layer "F.Fab")
			(hide yes)
			(effects
				(font
					(size 1.016 1.016)
					(thickness 0.1524)
				)
			)
		)
		(property "Device Type" "R402H16"
			(at 0.064008 -5.517896 270)
			(unlocked yes)
			(layer "F.Fab")
			(hide yes)
			(effects
				(font
					(size 1.016 1.016)
					(thickness 0.1524)
				)
			)
		)
		(duplicate_pad_numbers_are_jumpers no)
		(fp_line
			(start -0.508 -0.9398)
			(end -0.508 0.9398)
			(stroke
				(width 0.1524)
				(type default)
			)
			(layer "F.SilkS")
		)
		(fp_line
			(start 0.508 -0.9398)
			(end -0.508 -0.9398)
			(stroke
				(width 0.1524)
				(type default)
			)
			(layer "F.SilkS")
		)
		(fp_rect
			(start -0.508 0.9398)
			(end 0.508 -0.9398)
			(stroke
				(width 0)
				(type default)
			)
			(fill no)
			(layer "F.CrtYd")
		)
		(fp_rect
			(start -0.508 0.9398)
			(end 0.508 -0.9398)
			(stroke
				(width 0)
				(type default)
			)
			(fill no)
			(layer "F.Fab")
		)
		(pad "1" smd custom
			(at 0 -0.4445 270)
			(size 0.1397 0.1397)
			(layers "F.Cu" "F.Mask" "F.Paste")
			(net "PM8536_HB")
			(options
				(clearance outline)
				(anchor circle)
			)
			(primitives
				(gr_poly
					(pts
						(arc
							(start -0.1778 -0.2794)
							(mid -0.249642 -0.249642)
							(end -0.2794 -0.1778)
						)
						(arc
							(start -0.2794 0.1778)
							(mid -0.249642 0.249642)
							(end -0.1778 0.2794)
						)
						(arc
							(start 0.1778 0.2794)
							(mid 0.249642 0.249642)
							(end 0.2794 0.1778)
						)
						(arc
							(start 0.2794 -0.1778)
							(mid 0.249642 -0.249642)
							(end 0.1778 -0.2794)
						)
					)
					(width 0)
					(fill yes)
				)
			)
		)
		(pad "2" smd custom
			(at 0 0.4445 270)
			(size 0.1397 0.1397)
			(layers "F.Cu" "F.Mask" "F.Paste")
			(net "Q22_G")
			(options
				(clearance outline)
				(anchor circle)
			)
			(primitives
				(gr_poly
					(pts
						(arc
							(start -0.1778 -0.2794)
							(mid -0.249642 -0.249642)
							(end -0.2794 -0.1778)
						)
						(arc
							(start -0.2794 0.1778)
							(mid -0.249642 0.249642)
							(end -0.1778 0.2794)
						)
						(arc
							(start 0.1778 0.2794)
							(mid 0.249642 0.249642)
							(end 0.2794 0.1778)
						)
						(arc
							(start 0.2794 -0.1778)
							(mid 0.249642 -0.249642)
							(end 0.1778 -0.2794)
						)
					)
					(width 0)
					(fill yes)
				)
			)
		)
	)
	(footprint ""
		(layer "F.Cu")
		(at 21.9964 -149.9362 -90)
		(property "Reference" "C264"
			(at 0 0 270)
			(layer "F.SilkS")
			(hide yes)
			(effects
				(font
					(size 1.27 1.27)
				)
			)
		)
		(property "Value" "SC1U10V2KX-4-GP"
			(at 1.1811 -2.7051 270)
			(unlocked yes)
			(layer "F.Fab")
			(hide yes)
			(effects
				(font
					(size 1.016 1.016)
					(thickness 0.1524)
				)
			)
		)
		(property "Device Type" "C402H22"
			(at 1.1811 -4.2291 270)
			(unlocked yes)
			(layer "F.Fab")
			(hide yes)
			(effects
				(font
					(size 1.016 1.016)
					(thickness 0.1524)
				)
			)
		)
		(duplicate_pad_numbers_are_jumpers no)
		(fp_rect
			(start -0.4318 0.9525)
			(end 0.4318 -0.9525)
			(stroke
				(width 0)
				(type default)
			)
			(fill no)
			(layer "F.CrtYd")
		)
		(fp_rect
			(start -0.4318 0.9525)
			(end 0.4318 -0.9525)
			(stroke
				(width 0)
				(type default)
			)
			(fill no)
			(layer "F.Fab")
		)
		(pad "1" smd custom
			(at 0 -0.4445 270)
			(size 0.1524 0.1524)
			(layers "F.Cu" "F.Mask" "F.Paste")
			(net "U80_B")
			(options
				(clearance outline)
				(anchor circle)
			)
			(primitives
				(gr_poly
					(pts
						(arc
							(start 0.3048 -0.2032)
							(mid 0.275042 -0.275042)
							(end 0.2032 -0.3048)
						)
						(arc
							(start -0.2032 -0.3048)
							(mid -0.275042 -0.275042)
							(end -0.3048 -0.2032)
						)
						(arc
							(start -0.3048 0.2032)
							(mid -0.275042 0.275042)
							(end -0.2032 0.3048)
						)
						(arc
							(start 0.2032 0.3048)
							(mid 0.275042 0.275042)
							(end 0.3048 0.2032)
						)
					)
					(width 0)
					(fill yes)
				)
			)
		)
		(pad "2" smd custom
			(at 0 0.4445 270)
			(size 0.1524 0.1524)
			(layers "F.Cu" "F.Mask" "F.Paste")
			(net "GND")
			(options
				(clearance outline)
				(anchor circle)
			)
			(primitives
				(gr_poly
					(pts
						(arc
							(start 0.3048 -0.2032)
							(mid 0.275042 -0.275042)
							(end 0.2032 -0.3048)
						)
						(arc
							(start -0.2032 -0.3048)
							(mid -0.275042 -0.275042)
							(end -0.3048 -0.2032)
						)
						(arc
							(start -0.3048 0.2032)
							(mid -0.275042 0.275042)
							(end -0.2032 0.3048)
						)
						(arc
							(start 0.2032 0.3048)
							(mid 0.275042 0.275042)
							(end 0.3048 0.2032)
						)
					)
					(width 0)
					(fill yes)
				)
			)
		)
	)
	(footprint ""
		(layer "F.Cu")
		(at 16.764 -152.4)
		(property "Reference" "R489"
			(at 0 0 0)
			(layer "F.SilkS")
			(hide yes)
			(effects
				(font
					(size 1.27 1.27)
				)
			)
		)
		(property "Value" "4K7R2F-GP"
			(at 0.064008 -3.993896 0)
			(unlocked yes)
			(layer "F.Fab")
			(hide yes)
			(effects
				(font
					(size 1.016 1.016)
					(thickness 0.1524)
				)
			)
		)
		(property "Device Type" "R402H16"
			(at 0.064008 -5.517896 0)
			(unlocked yes)
			(layer "F.Fab")
			(hide yes)
			(effects
				(font
					(size 1.016 1.016)
					(thickness 0.1524)
				)
			)
		)
		(duplicate_pad_numbers_are_jumpers no)
		(fp_line
			(start -0.508 -0.9398)
			(end -0.508 0.9398)
			(stroke
				(width 0.1524)
				(type default)
			)
			(layer "F.SilkS")
		)
		(fp_line
			(start 0.508 -0.9398)
			(end -0.508 -0.9398)
			(stroke
				(width 0.1524)
				(type default)
			)
			(layer "F.SilkS")
		)
		(fp_rect
			(start -0.508 0.9398)
			(end 0.508 -0.9398)
			(stroke
				(width 0)
				(type default)
			)
			(fill no)
			(layer "F.CrtYd")
		)
		(fp_rect
			(start -0.508 0.9398)
			(end 0.508 -0.9398)
			(stroke
				(width 0)
				(type default)
			)
			(fill no)
			(layer "F.Fab")
		)
		(pad "1" smd custom
			(at 0 -0.4445)
			(size 0.1397 0.1397)
			(layers "F.Cu" "F.Mask" "F.Paste")
			(net "P1V53_STBY")
			(options
				(clearance outline)
				(anchor circle)
			)
			(primitives
				(gr_poly
					(pts
						(arc
							(start -0.1778 -0.2794)
							(mid -0.249642 -0.249642)
							(end -0.2794 -0.1778)
						)
						(arc
							(start -0.2794 0.1778)
							(mid -0.249642 0.249642)
							(end -0.1778 0.2794)
						)
						(arc
							(start 0.1778 0.2794)
							(mid 0.249642 0.249642)
							(end 0.2794 0.1778)
						)
						(arc
							(start 0.2794 -0.1778)
							(mid 0.249642 -0.249642)
							(end 0.1778 -0.2794)
						)
					)
					(width 0)
					(fill yes)
				)
			)
		)
		(pad "2" smd custom
			(at 0 0.4445)
			(size 0.1397 0.1397)
			(layers "F.Cu" "F.Mask" "F.Paste")
			(net "BMC_DDR3_RST_N")
			(options
				(clearance outline)
				(anchor circle)
			)
			(primitives
				(gr_poly
					(pts
						(arc
							(start -0.1778 -0.2794)
							(mid -0.249642 -0.249642)
							(end -0.2794 -0.1778)
						)
						(arc
							(start -0.2794 0.1778)
							(mid -0.249642 0.249642)
							(end -0.1778 0.2794)
						)
						(arc
							(start 0.1778 0.2794)
							(mid 0.249642 0.249642)
							(end 0.2794 0.1778)
						)
						(arc
							(start 0.2794 -0.1778)
							(mid 0.249642 -0.249642)
							(end 0.1778 -0.2794)
						)
					)
					(width 0)
					(fill yes)
				)
			)
		)
	)
)
